# T6G (Grand Teton) — schematic netlist excerpt (pin names and nets, part order shuffled) for the footprints in the layout excerpt that follows; sources: Cadence DE-HDL packaged netlist, KiCad conversion of 04192023_DAF0TMB3IC0_F0TG_MB_C_brd_V02_OCP.brd

C2067  Q_CAP  0.1UF 25V 10% X7R  pkg 0402  page 236 : A = P3V3_AUX ; B = GND
R1258  Q_RES  0 5% EMPTY  pkg 0402LF  page 258 : A = P1V8_AUX_ADC ; B = P1V8_AUX_ADC_MAM
PC515_1  Q_CAP  22UF 16V 20% X6S  pkg C0805  page 225 : A = SW_P12V_AUX_PVDD11_S3_P1_FLT ; B = GND

(kicad_pcb
	(version 20260206)
	(generator "pcbnew")
	(generator_version "10.0")
	(general
		(thickness 1.6)
		(legacy_teardrops no)
	)
	(paper "A4")
	(title_block
		(title "04192023_DAF0TMB3IC0_F0TG_MB_C_brd_V02_OCP.brd")
		(comment 1 "Grand Teton / footprints 7077-7079 of 8354")
	)
	(layers
		(0 "F.Cu" signal "TOP")
		(4 "In1.Cu" signal "GND")
		(6 "In2.Cu" signal "IN1")
		(8 "In3.Cu" signal "GND1")
		(10 "In4.Cu" signal "IN2")
		(12 "In5.Cu" signal "GND2")
		(14 "In6.Cu" signal "IN3")
		(16 "In7.Cu" signal "GND3")
		(18 "In8.Cu" signal "VCC")
		(20 "In9.Cu" signal "VCC1")
		(22 "In10.Cu" signal "GND4")
		(24 "In11.Cu" signal "IN4")
		(26 "In12.Cu" signal "GND5")
		(28 "In13.Cu" signal "IN5")
		(30 "In14.Cu" signal "GND6")
		(32 "In15.Cu" signal "IN6")
		(34 "In16.Cu" signal "GND7")
		(2 "B.Cu" signal "BOTTOM")
		(9 "F.Adhes" user "F.Adhesive")
		(11 "B.Adhes" user "B.Adhesive")
		(13 "F.Paste" user "Package Geometry/Pastemask Top")
		(15 "B.Paste" user "Package Geometry/Pastemask Bottom")
		(5 "F.SilkS" user "Ref Des/Silkscreen Top")
		(7 "B.SilkS" user "Ref Des/Silkscreen Bottom")
		(1 "F.Mask" user "Board Geometry/Soldermask Top")
		(3 "B.Mask" user "Board Geometry/Soldermask Bottom")
		(17 "Dwgs.User" user "User.Drawings")
		(19 "Cmts.User" user "User.Comments")
		(21 "Eco1.User" user "User.Eco1")
		(23 "Eco2.User" user "User.Eco2")
		(25 "Edge.Cuts" user "Board Geometry/Outline")
		(27 "Margin" user)
		(31 "F.CrtYd" user "Package Geometry/Place Bound Top")
		(29 "B.CrtYd" user "Package Geometry/Place Bound Bottom")
		(35 "F.Fab" user "Ref Des/Assembly Top")
		(33 "B.Fab" user "Ref Des/Assembly Bottom")
	)
	(footprint ""
		(layer "B.Cu")
		(at 231.943148 -322.84035 180)
		(property "Reference" "R1258"
			(at 0 0 0)
			(layer "B.SilkS")
			(hide yes)
			(effects
				(font
					(size 1.27 1.27)
				)
				(justify mirror)
			)
		)
		(property "Value" ""
			(at 0 0 0)
			(layer "B.Fab")
			(effects
				(font
					(size 1.27 1.27)
				)
				(justify mirror)
			)
		)
		(duplicate_pad_numbers_are_jumpers no)
		(fp_line
			(start 0.7874 0.4064)
			(end 0.7874 -0.4064)
			(stroke
				(width 0.1524)
				(type default)
			)
			(layer "B.SilkS")
		)
		(fp_line
			(start 0.7874 -0.4064)
			(end -0.7874 -0.4064)
			(stroke
				(width 0.1524)
				(type default)
			)
			(layer "B.SilkS")
		)
		(fp_line
			(start -0.7874 0.4064)
			(end 0.7874 0.4064)
			(stroke
				(width 0.1524)
				(type default)
			)
			(layer "B.SilkS")
		)
		(fp_line
			(start -0.7874 -0.4064)
			(end -0.7874 0.4064)
			(stroke
				(width 0.1524)
				(type default)
			)
			(layer "B.SilkS")
		)
		(fp_line
			(start 0.67945 0.3048)
			(end 0.67945 -0.305054)
			(stroke
				(width 0.1)
				(type default)
			)
			(layer "B.Fab")
		)
		(fp_line
			(start 0.67945 -0.305054)
			(end 0.12065 -0.305054)
			(stroke
				(width 0.1)
				(type default)
			)
			(layer "B.Fab")
		)
		(fp_line
			(start 0.12065 0.3048)
			(end 0.67945 0.3048)
			(stroke
				(width 0.1)
				(type default)
			)
			(layer "B.Fab")
		)
		(fp_line
			(start 0.12065 0.2794)
			(end 0.12065 0.3048)
			(stroke
				(width 0.1)
				(type default)
			)
			(layer "B.Fab")
		)
		(fp_line
			(start 0.12065 -0.2794)
			(end -0.12065 -0.2794)
			(stroke
				(width 0.1)
				(type default)
			)
			(layer "B.Fab")
		)
		(fp_line
			(start 0.12065 -0.305054)
			(end 0.12065 -0.2794)
			(stroke
				(width 0.1)
				(type default)
			)
			(layer "B.Fab")
		)
		(fp_line
			(start -0.120396 0.3048)
			(end -0.120396 0.2794)
			(stroke
				(width 0.1)
				(type default)
			)
			(layer "B.Fab")
		)
		(fp_line
			(start -0.120396 0.2794)
			(end 0.12065 0.2794)
			(stroke
				(width 0.1)
				(type default)
			)
			(layer "B.Fab")
		)
		(fp_line
			(start -0.12065 -0.2794)
			(end -0.12065 -0.3048)
			(stroke
				(width 0.1)
				(type default)
			)
			(layer "B.Fab")
		)
		(fp_line
			(start -0.12065 -0.3048)
			(end -0.67945 -0.3048)
			(stroke
				(width 0.1)
				(type default)
			)
			(layer "B.Fab")
		)
		(fp_line
			(start -0.67945 0.3048)
			(end -0.120396 0.3048)
			(stroke
				(width 0.1)
				(type default)
			)
			(layer "B.Fab")
		)
		(fp_line
			(start -0.67945 -0.3048)
			(end -0.67945 0.3048)
			(stroke
				(width 0.1)
				(type default)
			)
			(layer "B.Fab")
		)
		(pad "1" smd rect
			(at 0.40005 0 180)
			(size 0.4572 0.508)
			(layers "B.Cu" "B.Mask" "B.Paste")
			(net "P1V8_AUX_ADC")
		)
		(pad "2" smd rect
			(at -0.40005 0 180)
			(size 0.4572 0.508)
			(layers "B.Cu" "B.Mask" "B.Paste")
			(net "P1V8_AUX_ADC_MAM")
		)
	)
	(footprint ""
		(layer "B.Cu")
		(at 186.007502 -351.21342 90)
		(property "Reference" "PC515_1"
			(at 0 0 90)
			(layer "B.SilkS")
			(hide yes)
			(effects
				(font
					(size 1.27 1.27)
				)
				(justify mirror)
			)
		)
		(property "Value" ""
			(at 0 0 90)
			(layer "B.Fab")
			(effects
				(font
					(size 1.27 1.27)
				)
				(justify mirror)
			)
		)
		(duplicate_pad_numbers_are_jumpers no)
		(fp_line
			(start 1.524 -0.762)
			(end -1.524 -0.762)
			(stroke
				(width 0.1524)
				(type default)
			)
			(layer "B.SilkS")
		)
		(fp_line
			(start -1.524 -0.762)
			(end -1.524 0.762)
			(stroke
				(width 0.1524)
				(type default)
			)
			(layer "B.SilkS")
		)
		(fp_line
			(start 1.524 0.762)
			(end 1.524 -0.762)
			(stroke
				(width 0.1524)
				(type default)
			)
			(layer "B.SilkS")
		)
		(fp_line
			(start -1.524 0.762)
			(end 1.524 0.762)
			(stroke
				(width 0.1524)
				(type default)
			)
			(layer "B.SilkS")
		)
		(fp_line
			(start 1.1049 -0.724916)
			(end 1.1049 0.724916)
			(stroke
				(width 0.1)
				(type default)
			)
			(layer "B.Fab")
		)
		(fp_line
			(start -1.1049 -0.724916)
			(end 1.1049 -0.724916)
			(stroke
				(width 0.1)
				(type default)
			)
			(layer "B.Fab")
		)
		(fp_line
			(start 1.1049 0.724916)
			(end -1.1049 0.724916)
			(stroke
				(width 0.1)
				(type default)
			)
			(layer "B.Fab")
		)
		(fp_line
			(start -1.1049 0.724916)
			(end -1.1049 -0.724916)
			(stroke
				(width 0.1)
				(type default)
			)
			(layer "B.Fab")
		)
		(pad "1" smd rect
			(at 0.889 0 90)
			(size 1.016 1.27)
			(layers "B.Cu" "B.Mask" "B.Paste")
			(net "SW_P12V_AUX_PVDD11_S3_P1_FLT")
		)
		(pad "2" smd rect
			(at -0.889 0 90)
			(size 1.016 1.27)
			(layers "B.Cu" "B.Mask" "B.Paste")
			(net "GND")
		)
	)
	(footprint ""
		(layer "B.Cu")
		(at 216.20988 -53.177948)
		(property "Reference" "C2067"
			(at 0 0 0)
			(layer "B.SilkS")
			(hide yes)
			(effects
				(font
					(size 1.27 1.27)
				)
				(justify mirror)
			)
		)
		(property "Value" ""
			(at 0 0 0)
			(layer "B.Fab")
			(effects
				(font
					(size 1.27 1.27)
				)
				(justify mirror)
			)
		)
		(duplicate_pad_numbers_are_jumpers no)
		(fp_line
			(start -0.7874 -0.4064)
			(end -0.7874 0.4064)
			(stroke
				(width 0.1524)
				(type default)
			)
			(layer "B.SilkS")
		)
		(fp_line
			(start -0.7874 0.4064)
			(end 0.7874 0.4064)
			(stroke
				(width 0.1524)
				(type default)
			)
			(layer "B.SilkS")
		)
		(fp_line
			(start 0.7874 -0.4064)
			(end -0.7874 -0.4064)
			(stroke
				(width 0.1524)
				(type default)
			)
			(layer "B.SilkS")
		)
		(fp_line
			(start 0.7874 0.4064)
			(end 0.7874 -0.4064)
			(stroke
				(width 0.1524)
				(type default)
			)
			(layer "B.SilkS")
		)
		(fp_line
			(start -0.67945 -0.3048)
			(end -0.67945 0.3048)
			(stroke
				(width 0.1)
				(type default)
			)
			(layer "B.Fab")
		)
		(fp_line
			(start -0.67945 0.3048)
			(end -0.120396 0.3048)
			(stroke
				(width 0.1)
				(type default)
			)
			(layer "B.Fab")
		)
		(fp_line
			(start -0.12065 -0.3048)
			(end -0.67945 -0.3048)
			(stroke
				(width 0.1)
				(type default)
			)
			(layer "B.Fab")
		)
		(fp_line
			(start -0.12065 -0.2794)
			(end -0.12065 -0.3048)
			(stroke
				(width 0.1)
				(type default)
			)
			(layer "B.Fab")
		)
		(fp_line
			(start -0.120396 0.2794)
			(end 0.12065 0.2794)
			(stroke
				(width 0.1)
				(type default)
			)
			(layer "B.Fab")
		)
		(fp_line
			(start -0.120396 0.3048)
			(end -0.120396 0.2794)
			(stroke
				(width 0.1)
				(type default)
			)
			(layer "B.Fab")
		)
		(fp_line
			(start 0.12065 -0.305054)
			(end 0.12065 -0.2794)
			(stroke
				(width 0.1)
				(type default)
			)
			(layer "B.Fab")
		)
		(fp_line
			(start 0.12065 -0.2794)
			(end -0.12065 -0.2794)
			(stroke
				(width 0.1)
				(type default)
			)
			(layer "B.Fab")
		)
		(fp_line
			(start 0.12065 0.2794)
			(end 0.12065 0.3048)
			(stroke
				(width 0.1)
				(type default)
			)
			(layer "B.Fab")
		)
		(fp_line
			(start 0.12065 0.3048)
			(end 0.67945 0.3048)
			(stroke
				(width 0.1)
				(type default)
			)
			(layer "B.Fab")
		)
		(fp_line
			(start 0.67945 -0.305054)
			(end 0.12065 -0.305054)
			(stroke
				(width 0.1)
				(type default)
			)
			(layer "B.Fab")
		)
		(fp_line
			(start 0.67945 0.3048)
			(end 0.67945 -0.305054)
			(stroke
				(width 0.1)
				(type default)
			)
			(layer "B.Fab")
		)
		(pad "1" smd circle
			(at 0.40005 0 180)
			(size 0 0)
			(layers "B.Cu" "B.Mask" "B.Paste")
			(net "P3V3_AUX")
		)
		(pad "2" smd circle
			(at -0.40005 0 180)
			(size 0 0)
			(layers "B.Cu" "B.Mask" "B.Paste")
			(net "GND")
		)
	)
)
